# BASEBOARD_FAB2 (Tioga Pass) — schematic netlist excerpt (pin names and nets, part order shuffled) for the footprints in the layout excerpt that follows; sources: Cadence DE-HDL packaged netlist, KiCad conversion of Wiwynn_Tioga_Pass_MB.brd

EU4D5  PXE1110B  IC  pkg QFN  page 213
  DNC(0)  = NC
  DNC(1)  = NC
  BPWM1  = NC
  DNC(2)  = NC
  APWM1  = VR_PVCCIO_CPU1_PWM1
  SDA  = SMB_VR_STBY_LVC3_SDA
  SCL  = SMB_VR_STBY_LVC3_SCL
  RESET_N  = NC
  AVRRDY  = PWRGD_PVCCIO_CPU1_R
  AVREN  = VR_PVCCIO_CPU1_EN
  VRHOT_N  = IRQ_PVCCIO_CPU1_VRHOT_N
  PINALRT_N  = NC
  MP0  = NC
  MP1  = NC
  VCLK  = SVID_CLK_PVCCIO_CPU1
  VDIO  = SVID_VDIO_PVCCIO_CPU1
  VALRT_N  = SVID_ALERT_PVCCIO_CPU1
  MP2  = NC
  AVSEN  = VR_PVCCIO_CPU1_AVSP
  AVREF  = VSENSE_PVCCIO_CPU1_AVSN
  AIREF1  = VR_PVCCIO_CPU1_AIREF1
  AISEN1  = ISENSE_PVCCIO_CPU1_PH1_IMON
  GND(1)  = GND
  DNC(3)  = NC
  BIREF1  = NC
  BISEN1  = GND
  GND(0)  = GND
  DNC(4)  = NC
  BVSEN  = NC
  BVREF  = NC
  MP3  = NC
  MP4  = PU_VR_PVCCIO_CPU1_FAULT1
  XADDR2  = VR_PVCCIO_CPU1_XADDR2
  BTSEN  = NC
  ATSEN  = A_TSENSE_PVCCIO_CPU1
  XADDR1  = VR_PVCCIO_CPU1_XADDR1
  VINSEN  = VR_PVCCIO_CPU1_VINSEN
  IINSEN  = NC
  VDD  = VR_PVCCIO_CPU1_VDD
  VD12  = VR_PVCCIO_CPU1_VD12
  THPAD  = GND

(kicad_pcb
	(version 20260206)
	(generator "pcbnew")
	(generator_version "10.0")
	(general
		(thickness 1.6)
		(legacy_teardrops no)
	)
	(paper "A4")
	(title_block
		(title "Wiwynn_Tioga_Pass_MB.brd")
		(comment 1 "Tioga Pass / footprint 313 of 4770 (EU4D5), pads 1-17 of 41")
	)
	(layers
		(0 "F.Cu" signal "TOP")
		(4 "In1.Cu" signal "L2GND")
		(6 "In2.Cu" signal "L3")
		(8 "In3.Cu" signal "L4GND")
		(10 "In4.Cu" signal "L5")
		(12 "In5.Cu" signal "L6GND")
		(14 "In6.Cu" signal "L7VCC")
		(16 "In7.Cu" signal "L8VCC")
		(18 "In8.Cu" signal "L9GND")
		(20 "In9.Cu" signal "L10")
		(22 "In10.Cu" signal "L11GND")
		(24 "In11.Cu" signal "L12")
		(26 "In12.Cu" signal "L13GND")
		(2 "B.Cu" signal "BOTTOM")
		(9 "F.Adhes" user "F.Adhesive")
		(11 "B.Adhes" user "B.Adhesive")
		(13 "F.Paste" user "Package Geometry/Pastemask Top")
		(15 "B.Paste" user "Package Geometry/Pastemask Bottom")
		(5 "F.SilkS" user "Ref Des/Silkscreen Top")
		(7 "B.SilkS" user "Ref Des/Silkscreen Bottom")
		(1 "F.Mask" user "Board Geometry/Soldermask Top")
		(3 "B.Mask" user "Board Geometry/Soldermask Bottom")
		(17 "Dwgs.User" user "User.Drawings")
		(19 "Cmts.User" user "User.Comments")
		(21 "Eco1.User" user "User.Eco1")
		(23 "Eco2.User" user "User.Eco2")
		(25 "Edge.Cuts" user "Board Geometry/Outline")
		(27 "Margin" user)
		(31 "F.CrtYd" user "Package Geometry/Place Bound Top")
		(29 "B.CrtYd" user "Package Geometry/Place Bound Bottom")
		(35 "F.Fab" user "Ref Des/Assembly Top")
		(33 "B.Fab" user "Ref Des/Assembly Bottom")
	)
	(footprint ""
		(layer "F.Cu")
		(at 169.1894 -66.802 -90)
		(property "Reference" "EU4D5"
			(at 0.6096 -3.60807 90)
			(unlocked yes)
			(layer "F.SilkS")
			(effects
				(font
					(size 0.7874 0.5842)
					(thickness 0.1524)
				)
				(justify left)
			)
		)
		(property "Value" ""
			(at 0 0 270)
			(layer "F.Fab")
			(effects
				(font
					(size 1.27 1.27)
				)
			)
		)
		(duplicate_pad_numbers_are_jumpers no)
		(pad "1" smd custom
			(at -2.4511 -1.800098 270)
			(size 0.0508 0.0508)
			(layers "F.Cu" "F.Mask" "F.Paste")
			(net "Net_336")
			(options
				(clearance outline)
				(anchor circle)
			)
			(primitives
				(gr_poly
					(pts
						(arc
							(start 0.254 -0.1016)
							(mid 0.3556 0)
							(end 0.254 0.1016)
						)
						(xy -0.3556 0.1016) (xy -0.3556 -0.1016)
					)
					(width 0)
					(fill yes)
				)
			)
		)
		(pad "2" smd custom
			(at -2.4511 -1.400048 270)
			(size 0.0508 0.0508)
			(layers "F.Cu" "F.Mask" "F.Paste")
			(net "Net_337")
			(options
				(clearance outline)
				(anchor circle)
			)
			(primitives
				(gr_poly
					(pts
						(arc
							(start 0.254 -0.1016)
							(mid 0.3556 0)
							(end 0.254 0.1016)
						)
						(xy -0.3556 0.1016) (xy -0.3556 -0.1016)
					)
					(width 0)
					(fill yes)
				)
			)
		)
		(pad "3" smd custom
			(at -2.4511 -0.999998 270)
			(size 0.0508 0.0508)
			(layers "F.Cu" "F.Mask" "F.Paste")
			(net "Net_279")
			(options
				(clearance outline)
				(anchor circle)
			)
			(primitives
				(gr_poly
					(pts
						(arc
							(start 0.254 -0.1016)
							(mid 0.3556 0)
							(end 0.254 0.1016)
						)
						(xy -0.3556 0.1016) (xy -0.3556 -0.1016)
					)
					(width 0)
					(fill yes)
				)
			)
		)
		(pad "4" smd custom
			(at -2.4511 -0.599948 270)
			(size 0.0508 0.0508)
			(layers "F.Cu" "F.Mask" "F.Paste")
			(net "Net_338")
			(options
				(clearance outline)
				(anchor circle)
			)
			(primitives
				(gr_poly
					(pts
						(arc
							(start 0.254 -0.1016)
							(mid 0.3556 0)
							(end 0.254 0.1016)
						)
						(xy -0.3556 0.1016) (xy -0.3556 -0.1016)
					)
					(width 0)
					(fill yes)
				)
			)
		)
		(pad "5" smd custom
			(at -2.4511 -0.199898 270)
			(size 0.0508 0.0508)
			(layers "F.Cu" "F.Mask" "F.Paste")
			(net "VR_PVCCIO_CPU1_PWM1")
			(options
				(clearance outline)
				(anchor circle)
			)
			(primitives
				(gr_poly
					(pts
						(arc
							(start 0.254 -0.1016)
							(mid 0.3556 0)
							(end 0.254 0.1016)
						)
						(xy -0.3556 0.1016) (xy -0.3556 -0.1016)
					)
					(width 0)
					(fill yes)
				)
			)
		)
		(pad "6" smd custom
			(at -2.4511 0.199898 270)
			(size 0.0508 0.0508)
			(layers "F.Cu" "F.Mask" "F.Paste")
			(net "SMB_VR_STBY_LVC3_SDA")
			(options
				(clearance outline)
				(anchor circle)
			)
			(primitives
				(gr_poly
					(pts
						(arc
							(start 0.254 -0.1016)
							(mid 0.3556 0)
							(end 0.254 0.1016)
						)
						(xy -0.3556 0.1016) (xy -0.3556 -0.1016)
					)
					(width 0)
					(fill yes)
				)
			)
		)
		(pad "7" smd custom
			(at -2.4511 0.599948 270)
			(size 0.0508 0.0508)
			(layers "F.Cu" "F.Mask" "F.Paste")
			(net "SMB_VR_STBY_LVC3_SCL")
			(options
				(clearance outline)
				(anchor circle)
			)
			(primitives
				(gr_poly
					(pts
						(arc
							(start 0.254 -0.1016)
							(mid 0.3556 0)
							(end 0.254 0.1016)
						)
						(xy -0.3556 0.1016) (xy -0.3556 -0.1016)
					)
					(width 0)
					(fill yes)
				)
			)
		)
		(pad "8" smd custom
			(at -2.4511 0.999998 270)
			(size 0.0508 0.0508)
			(layers "F.Cu" "F.Mask" "F.Paste")
			(net "Net_280")
			(options
				(clearance outline)
				(anchor circle)
			)
			(primitives
				(gr_poly
					(pts
						(arc
							(start 0.254 -0.1016)
							(mid 0.3556 0)
							(end 0.254 0.1016)
						)
						(xy -0.3556 0.1016) (xy -0.3556 -0.1016)
					)
					(width 0)
					(fill yes)
				)
			)
		)
		(pad "9" smd custom
			(at -2.4511 1.400048 270)
			(size 0.0508 0.0508)
			(layers "F.Cu" "F.Mask" "F.Paste")
			(net "PWRGD_PVCCIO_CPU1_R")
			(options
				(clearance outline)
				(anchor circle)
			)
			(primitives
				(gr_poly
					(pts
						(arc
							(start 0.254 -0.1016)
							(mid 0.3556 0)
							(end 0.254 0.1016)
						)
						(xy -0.3556 0.1016) (xy -0.3556 -0.1016)
					)
					(width 0)
					(fill yes)
				)
			)
		)
		(pad "10" smd custom
			(at -2.4511 1.800098 270)
			(size 0.0508 0.0508)
			(layers "F.Cu" "F.Mask" "F.Paste")
			(net "VR_PVCCIO_CPU1_EN")
			(options
				(clearance outline)
				(anchor circle)
			)
			(primitives
				(gr_poly
					(pts
						(arc
							(start 0.254 -0.1016)
							(mid 0.3556 0)
							(end 0.254 0.1016)
						)
						(xy -0.3556 0.1016) (xy -0.3556 -0.1016)
					)
					(width 0)
					(fill yes)
				)
			)
		)
		(pad "11" smd custom
			(at -1.800098 2.4511 270)
			(size 0.0508 0.0508)
			(layers "F.Cu" "F.Mask" "F.Paste")
			(net "IRQ_PVCCIO_CPU1_VRHOT_N")
			(options
				(clearance outline)
				(anchor circle)
			)
			(primitives
				(gr_poly
					(pts
						(arc
							(start -0.1016 -0.254)
							(mid 0 -0.3556)
							(end 0.1016 -0.254)
						)
						(xy 0.1016 0.3556) (xy -0.1016 0.3556)
					)
					(width 0)
					(fill yes)
				)
			)
		)
		(pad "12" smd custom
			(at -1.400048 2.4511 270)
			(size 0.0508 0.0508)
			(layers "F.Cu" "F.Mask" "F.Paste")
			(net "Net_264")
			(options
				(clearance outline)
				(anchor circle)
			)
			(primitives
				(gr_poly
					(pts
						(arc
							(start -0.1016 -0.254)
							(mid 0 -0.3556)
							(end 0.1016 -0.254)
						)
						(xy 0.1016 0.3556) (xy -0.1016 0.3556)
					)
					(width 0)
					(fill yes)
				)
			)
		)
		(pad "13" smd custom
			(at -0.999998 2.4511 270)
			(size 0.0508 0.0508)
			(layers "F.Cu" "F.Mask" "F.Paste")
			(net "Net_262")
			(options
				(clearance outline)
				(anchor circle)
			)
			(primitives
				(gr_poly
					(pts
						(arc
							(start -0.1016 -0.254)
							(mid 0 -0.3556)
							(end 0.1016 -0.254)
						)
						(xy 0.1016 0.3556) (xy -0.1016 0.3556)
					)
					(width 0)
					(fill yes)
				)
			)
		)
		(pad "14" smd custom
			(at -0.599948 2.4511 270)
			(size 0.0508 0.0508)
			(layers "F.Cu" "F.Mask" "F.Paste")
			(net "Net_263")
			(options
				(clearance outline)
				(anchor circle)
			)
			(primitives
				(gr_poly
					(pts
						(arc
							(start -0.1016 -0.254)
							(mid 0 -0.3556)
							(end 0.1016 -0.254)
						)
						(xy 0.1016 0.3556) (xy -0.1016 0.3556)
					)
					(width 0)
					(fill yes)
				)
			)
		)
		(pad "15" smd custom
			(at -0.199898 2.4511 270)
			(size 0.0508 0.0508)
			(layers "F.Cu" "F.Mask" "F.Paste")
			(net "SVID_CLK_PVCCIO_CPU1")
			(options
				(clearance outline)
				(anchor circle)
			)
			(primitives
				(gr_poly
					(pts
						(arc
							(start -0.1016 -0.254)
							(mid 0 -0.3556)
							(end 0.1016 -0.254)
						)
						(xy 0.1016 0.3556) (xy -0.1016 0.3556)
					)
					(width 0)
					(fill yes)
				)
			)
		)
		(pad "16" smd custom
			(at 0.199898 2.4511 270)
			(size 0.0508 0.0508)
			(layers "F.Cu" "F.Mask" "F.Paste")
			(net "SVID_VDIO_PVCCIO_CPU1")
			(options
				(clearance outline)
				(anchor circle)
			)
			(primitives
				(gr_poly
					(pts
						(arc
							(start -0.1016 -0.254)
							(mid 0 -0.3556)
							(end 0.1016 -0.254)
						)
						(xy 0.1016 0.3556) (xy -0.1016 0.3556)
					)
					(width 0)
					(fill yes)
				)
			)
		)
		(pad "17" smd custom
			(at 0.599948 2.4511 270)
			(size 0.0508 0.0508)
			(layers "F.Cu" "F.Mask" "F.Paste")
			(net "SVID_ALERT_PVCCIO_CPU1")
			(options
				(clearance outline)
				(anchor circle)
			)
			(primitives
				(gr_poly
					(pts
						(arc
							(start -0.1016 -0.254)
							(mid 0 -0.3556)
							(end 0.1016 -0.254)
						)
						(xy 0.1016 0.3556) (xy -0.1016 0.3556)
					)
					(width 0)
					(fill yes)
				)
			)
		)
	)
)
